# T6G (Grand Teton) — schematic netlist excerpt (pin names and nets, part order shuffled) for the footprints in the layout excerpt that follows; sources: Cadence DE-HDL packaged netlist, KiCad conversion of 04192023_DAF0TMB3IC0_F0TG_MB_C_brd_V02_OCP.brd

R8179  Q_RES  0 5% CHIP  pkg 0402LF  page 210 : A = PVDDCR_CPU0_P1_EN ; B = PVDDCR_CPU0_P1_EN_R
C2007  Q_CAP  1UF 25V 10% X6S  pkg C0402  page 144 : A = P3V3_AUX ; B = GND

(kicad_pcb
	(version 20260206)
	(generator "pcbnew")
	(generator_version "10.0")
	(general
		(thickness 1.6)
		(legacy_teardrops no)
	)
	(paper "A4")
	(title_block
		(title "04192023_DAF0TMB3IC0_F0TG_MB_C_brd_V02_OCP.brd")
		(comment 1 "Grand Teton / footprints 812-813 of 8354")
	)
	(layers
		(0 "F.Cu" signal "TOP")
		(4 "In1.Cu" signal "GND")
		(6 "In2.Cu" signal "IN1")
		(8 "In3.Cu" signal "GND1")
		(10 "In4.Cu" signal "IN2")
		(12 "In5.Cu" signal "GND2")
		(14 "In6.Cu" signal "IN3")
		(16 "In7.Cu" signal "GND3")
		(18 "In8.Cu" signal "VCC")
		(20 "In9.Cu" signal "VCC1")
		(22 "In10.Cu" signal "GND4")
		(24 "In11.Cu" signal "IN4")
		(26 "In12.Cu" signal "GND5")
		(28 "In13.Cu" signal "IN5")
		(30 "In14.Cu" signal "GND6")
		(32 "In15.Cu" signal "IN6")
		(34 "In16.Cu" signal "GND7")
		(2 "B.Cu" signal "BOTTOM")
		(9 "F.Adhes" user "F.Adhesive")
		(11 "B.Adhes" user "B.Adhesive")
		(13 "F.Paste" user "Package Geometry/Pastemask Top")
		(15 "B.Paste" user "Package Geometry/Pastemask Bottom")
		(5 "F.SilkS" user "Ref Des/Silkscreen Top")
		(7 "B.SilkS" user "Ref Des/Silkscreen Bottom")
		(1 "F.Mask" user "Board Geometry/Soldermask Top")
		(3 "B.Mask" user "Board Geometry/Soldermask Bottom")
		(17 "Dwgs.User" user "User.Drawings")
		(19 "Cmts.User" user "User.Comments")
		(21 "Eco1.User" user "User.Eco1")
		(23 "Eco2.User" user "User.Eco2")
		(25 "Edge.Cuts" user "Board Geometry/Outline")
		(27 "Margin" user)
		(31 "F.CrtYd" user "Package Geometry/Place Bound Top")
		(29 "B.CrtYd" user "Package Geometry/Place Bound Bottom")
		(35 "F.Fab" user "Ref Des/Assembly Top")
		(33 "B.Fab" user "Ref Des/Assembly Bottom")
	)
	(footprint ""
		(layer "F.Cu")
		(at 147.16379 -102.294182 90)
		(property "Reference" "C2007"
			(at 0 0 90)
			(layer "F.SilkS")
			(hide yes)
			(effects
				(font
					(size 1.27 1.27)
				)
			)
		)
		(property "Value" ""
			(at 0 0 90)
			(layer "F.Fab")
			(effects
				(font
					(size 1.27 1.27)
				)
			)
		)
		(duplicate_pad_numbers_are_jumpers no)
		(fp_line
			(start 0.7874 -0.4064)
			(end 0.7874 0.4064)
			(stroke
				(width 0.1524)
				(type default)
			)
			(layer "F.SilkS")
		)
		(fp_line
			(start -0.7874 -0.4064)
			(end 0.7874 -0.4064)
			(stroke
				(width 0.1524)
				(type default)
			)
			(layer "F.SilkS")
		)
		(fp_line
			(start 0.7874 0.4064)
			(end -0.7874 0.4064)
			(stroke
				(width 0.1524)
				(type default)
			)
			(layer "F.SilkS")
		)
		(fp_line
			(start -0.7874 0.4064)
			(end -0.7874 -0.4064)
			(stroke
				(width 0.1524)
				(type default)
			)
			(layer "F.SilkS")
		)
		(fp_line
			(start -0.12065 -0.305054)
			(end -0.12065 -0.2794)
			(stroke
				(width 0.1)
				(type default)
			)
			(layer "F.Fab")
		)
		(fp_line
			(start -0.67945 -0.305054)
			(end -0.12065 -0.305054)
			(stroke
				(width 0.1)
				(type default)
			)
			(layer "F.Fab")
		)
		(fp_line
			(start 0.67945 -0.3048)
			(end 0.67945 0.3048)
			(stroke
				(width 0.1)
				(type default)
			)
			(layer "F.Fab")
		)
		(fp_line
			(start 0.12065 -0.3048)
			(end 0.67945 -0.3048)
			(stroke
				(width 0.1)
				(type default)
			)
			(layer "F.Fab")
		)
		(fp_line
			(start 0.12065 -0.2794)
			(end 0.12065 -0.3048)
			(stroke
				(width 0.1)
				(type default)
			)
			(layer "F.Fab")
		)
		(fp_line
			(start -0.12065 -0.2794)
			(end 0.12065 -0.2794)
			(stroke
				(width 0.1)
				(type default)
			)
			(layer "F.Fab")
		)
		(fp_line
			(start 0.120396 0.2794)
			(end -0.12065 0.2794)
			(stroke
				(width 0.1)
				(type default)
			)
			(layer "F.Fab")
		)
		(fp_line
			(start -0.12065 0.2794)
			(end -0.12065 0.3048)
			(stroke
				(width 0.1)
				(type default)
			)
			(layer "F.Fab")
		)
		(fp_line
			(start 0.67945 0.3048)
			(end 0.120396 0.3048)
			(stroke
				(width 0.1)
				(type default)
			)
			(layer "F.Fab")
		)
		(fp_line
			(start 0.120396 0.3048)
			(end 0.120396 0.2794)
			(stroke
				(width 0.1)
				(type default)
			)
			(layer "F.Fab")
		)
		(fp_line
			(start -0.12065 0.3048)
			(end -0.67945 0.3048)
			(stroke
				(width 0.1)
				(type default)
			)
			(layer "F.Fab")
		)
		(fp_line
			(start -0.67945 0.3048)
			(end -0.67945 -0.305054)
			(stroke
				(width 0.1)
				(type default)
			)
			(layer "F.Fab")
		)
		(pad "1" smd circle
			(at -0.40005 0 90)
			(size 0 0)
			(layers "F.Cu" "F.Mask" "F.Paste")
			(net "P3V3_AUX")
		)
		(pad "2" smd circle
			(at 0.40005 0 90)
			(size 0 0)
			(layers "F.Cu" "F.Mask" "F.Paste")
			(net "GND")
		)
	)
	(footprint ""
		(layer "F.Cu")
		(at 90.209878 -142.85341)
		(property "Reference" "R8179"
			(at 0 0 0)
			(layer "F.SilkS")
			(hide yes)
			(effects
				(font
					(size 1.27 1.27)
				)
			)
		)
		(property "Value" ""
			(at 0 0 0)
			(layer "F.Fab")
			(effects
				(font
					(size 1.27 1.27)
				)
			)
		)
		(duplicate_pad_numbers_are_jumpers no)
		(fp_line
			(start -0.7874 -0.4064)
			(end 0.7874 -0.4064)
			(stroke
				(width 0.1524)
				(type default)
			)
			(layer "F.SilkS")
		)
		(fp_line
			(start -0.7874 0.4064)
			(end -0.7874 -0.4064)
			(stroke
				(width 0.1524)
				(type default)
			)
			(layer "F.SilkS")
		)
		(fp_line
			(start 0.7874 -0.4064)
			(end 0.7874 0.4064)
			(stroke
				(width 0.1524)
				(type default)
			)
			(layer "F.SilkS")
		)
		(fp_line
			(start 0.7874 0.4064)
			(end -0.7874 0.4064)
			(stroke
				(width 0.1524)
				(type default)
			)
			(layer "F.SilkS")
		)
		(fp_line
			(start -0.67945 -0.305054)
			(end -0.12065 -0.305054)
			(stroke
				(width 0.1)
				(type default)
			)
			(layer "F.Fab")
		)
		(fp_line
			(start -0.67945 0.3048)
			(end -0.67945 -0.305054)
			(stroke
				(width 0.1)
				(type default)
			)
			(layer "F.Fab")
		)
		(fp_line
			(start -0.12065 -0.305054)
			(end -0.12065 -0.2794)
			(stroke
				(width 0.1)
				(type default)
			)
			(layer "F.Fab")
		)
		(fp_line
			(start -0.12065 -0.2794)
			(end 0.12065 -0.2794)
			(stroke
				(width 0.1)
				(type default)
			)
			(layer "F.Fab")
		)
		(fp_line
			(start -0.12065 0.2794)
			(end -0.12065 0.3048)
			(stroke
				(width 0.1)
				(type default)
			)
			(layer "F.Fab")
		)
		(fp_line
			(start -0.12065 0.3048)
			(end -0.67945 0.3048)
			(stroke
				(width 0.1)
				(type default)
			)
			(layer "F.Fab")
		)
		(fp_line
			(start 0.120396 0.2794)
			(end -0.12065 0.2794)
			(stroke
				(width 0.1)
				(type default)
			)
			(layer "F.Fab")
		)
		(fp_line
			(start 0.120396 0.3048)
			(end 0.120396 0.2794)
			(stroke
				(width 0.1)
				(type default)
			)
			(layer "F.Fab")
		)
		(fp_line
			(start 0.12065 -0.3048)
			(end 0.67945 -0.3048)
			(stroke
				(width 0.1)
				(type default)
			)
			(layer "F.Fab")
		)
		(fp_line
			(start 0.12065 -0.2794)
			(end 0.12065 -0.3048)
			(stroke
				(width 0.1)
				(type default)
			)
			(layer "F.Fab")
		)
		(fp_line
			(start 0.67945 -0.3048)
			(end 0.67945 0.3048)
			(stroke
				(width 0.1)
				(type default)
			)
			(layer "F.Fab")
		)
		(fp_line
			(start 0.67945 0.3048)
			(end 0.120396 0.3048)
			(stroke
				(width 0.1)
				(type default)
			)
			(layer "F.Fab")
		)
		(pad "1" smd circle
			(at -0.40005 0)
			(size 0 0)
			(layers "F.Cu" "F.Mask" "F.Paste")
			(net "PVDDCR_CPU0_P1_EN")
		)
		(pad "2" smd circle
			(at 0.40005 0)
			(size 0 0)
			(layers "F.Cu" "F.Mask" "F.Paste")
			(net "PVDDCR_CPU0_P1_EN_R")
		)
	)
)
